#ISCELL
  pure_quanta quanta_title_block_c *
  *
#CELL
  pure_quanta hole *
  page212_i10
#CELL
  pure_quanta conn1_10165288101lf *
  page212_i101
#CELL
  pure_quanta conn1_10165288101lf *
  page212_i106
#ISCELL
  pure_quanta_power universal_gnd *
  page212_i11
#CELL
  pure_quanta hole *
  page212_i111
#CELL
  pure_quanta hole *
  page212_i113
#ISCELL
  pure_quanta_power universal_gnd *
  page212_i114
#ISCELL
  pure_quanta_power universal_gnd *
  page212_i115
#CELL
  pure_quanta hole *
  page212_i116
#CELL
  pure_quanta hole *
  page212_i12
#CELL
  pure_quanta gnd_hole *
  page212_i120
#ISCELL
  pure_quanta_power universal_gnd *
  page212_i122
#CELL
  pure_quanta gnd_hole *
  page212_i123
#ISCELL
  pure_quanta_power universal_gnd *
  page212_i124
#CELL
  pure_quanta hole *
  page212_i125
#ISCELL
  pure_quanta_power universal_gnd *
  page212_i126
#CELL
  pure_quanta hole *
  page212_i127
#ISCELL
  pure_quanta_power universal_gnd *
  page212_i128
#CELL
  pure_quanta hole *
  page212_i129
#ISCELL
  pure_quanta_power universal_gnd *
  page212_i130
#ISCELL
  pure_quanta_power universal_gnd *
  page212_i131
#CELL
  pure_quanta hole *
  page212_i132
#CELL
  pure_quanta hole *
  page212_i133
#ISCELL
  pure_quanta_power universal_gnd *
  page212_i134
#CELL
  pure_quanta hole *
  page212_i135
#ISCELL
  pure_quanta_power universal_gnd *
  page212_i136
#ISCELL
  pure_quanta_power universal_gnd *
  page212_i137
#CELL
  pure_quanta hole *
  page212_i138
#ISCELL
  pure_quanta_power universal_gnd *
  page212_i139
#CELL
  pure_quanta hole *
  page212_i140
#CELL
  pure_quanta hole *
  page212_i141
#CELL
  pure_quanta hole *
  page212_i142
#ISCELL
  pure_quanta_power universal_gnd *
  page212_i143
#ISCELL
  pure_quanta_power universal_gnd *
  page212_i144
#CELL
  pure_quanta hole *
  page212_i145
#ISCELL
  pure_quanta_power universal_gnd *
  page212_i146
#CELL
  pure_quanta hole *
  page212_i147
#ISCELL
  pure_quanta_power universal_gnd *
  page212_i148
#CELL
  pure_quanta hole *
  page212_i149
#ISCELL
  pure_quanta_power universal_gnd *
  page212_i150
#ISCELL
  pure_quanta_power universal_gnd *
  page212_i151
#CELL
  pure_quanta hole *
  page212_i152
#CELL
  pure_quanta hole *
  page212_i153
#ISCELL
  pure_quanta_power universal_gnd *
  page212_i154
#ISCELL
  pure_quanta_power universal_gnd *
  page212_i155
#CELL
  pure_quanta hole *
  page212_i156
#CELL
  pure_quanta hole *
  page212_i157
#ISCELL
  pure_quanta_power universal_gnd *
  page212_i158
#CELL
  pure_quanta hole *
  page212_i159
#ISCELL
  pure_quanta_power universal_gnd *
  page212_i160
#CELL
  pure_quanta hole *
  page212_i161
#ISCELL
  pure_quanta_power universal_gnd *
  page212_i162
#CELL
  pure_quanta hole *
  page212_i163
#ISCELL
  pure_quanta_power universal_gnd *
  page212_i164
#ISCELL
  pure_quanta_power universal_gnd *
  page212_i165
#CELL
  pure_quanta hole *
  page212_i166
#CELL
  pure_quanta hole *
  page212_i167
#CELL
  pure_quanta hole *
  page212_i168
#ISCELL
  pure_quanta_power universal_gnd *
  page212_i169
#CELL
  pure_quanta hole *
  page212_i170
#ISCELL
  pure_quanta_power universal_gnd *
  page212_i171
#CELL
  pure_quanta hole *
  page212_i176
#ISCELL
  pure_quanta_power universal_gnd *
  page212_i177
#CELL
  pure_quanta hole *
  page212_i178
#ISCELL
  pure_quanta_power universal_gnd *
  page212_i179
#ISCELL
  pure_quanta_power universal_gnd *
  page212_i186
#CELL
  pure_quanta hole *
  page212_i187
#ISCELL
  pure_quanta_power universal_gnd *
  page212_i192
#CELL
  pure_quanta hole *
  page212_i193
#ISCELL
  pure_quanta_power universal_gnd *
  page212_i194
#CELL
  pure_quanta hole *
  page212_i195
#ISCELL
  pure_quanta_power universal_gnd *
  page212_i21
#ISCELL
  pure_quanta_power universal_gnd *
  page212_i24
#CELL
  pure_quanta gnd_hole *
  page212_i25
#CELL
  pure_quanta hole *
  page212_i26
#CELL
  pure_quanta hole *
  page212_i27
#ISCELL
  pure_quanta_power universal_gnd *
  page212_i28
#ISCELL
  pure_quanta_power universal_gnd *
  page212_i29
#ISCELL
  pure_quanta_power universal_gnd *
  page212_i3
#CELL
  pure_quanta gnd_hole *
  page212_i30
#CELL
  pure_quanta hole *
  page212_i31
#ISCELL
  pure_quanta_power universal_gnd *
  page212_i32
#CELL
  pure_quanta hole *
  page212_i33
#ISCELL
  pure_quanta_power universal_gnd *
  page212_i34
#ISCELL
  pure_quanta_power universal_gnd *
  page212_i35
#CELL
  pure_quanta hole *
  page212_i36
#ISCELL
  pure_quanta_power universal_gnd *
  page212_i37
#CELL
  pure_quanta hole *
  page212_i38
#ISCELL
  pure_quanta_power universal_gnd *
  page212_i39
#CELL
  pure_quanta hole *
  page212_i4
#CELL
  pure_quanta hole *
  page212_i40
#CELL
  pure_quanta hole *
  page212_i41
#ISCELL
  pure_quanta_power universal_gnd *
  page212_i42
#CELL
  pure_quanta gnd_hole *
  page212_i43
#ISCELL
  pure_quanta_power universal_gnd *
  page212_i44
#CELL
  pure_quanta hole *
  page212_i45
#CELL
  pure_quanta hole *
  page212_i46
#ISCELL
  pure_quanta_power universal_gnd *
  page212_i47
#ISCELL
  pure_quanta_power universal_gnd *
  page212_i48
#CELL
  pure_quanta hole *
  page212_i49
#CELL
  pure_quanta hole *
  page212_i5
#CELL
  pure_quanta hole *
  page212_i50
#CELL
  pure_quanta hole *
  page212_i51
#CELL
  pure_quanta hole *
  page212_i52
#ISCELL
  pure_quanta_power universal_gnd *
  page212_i53
#ISCELL
  pure_quanta_power universal_gnd *
  page212_i54
#CELL
  pure_quanta hole *
  page212_i55
#CELL
  pure_quanta hole *
  page212_i56
#ISCELL
  pure_quanta_power universal_gnd *
  page212_i6
#CELL
  pure_quanta hole *
  page212_i7
#ISCELL
  pure_quanta_power universal_gnd *
  page212_i8
#CELL
  pure_quanta hole *
  page212_i84
#CELL
  pure_quanta hole *
  page212_i85
#ISCELL
  pure_quanta_power universal_gnd *
  page212_i86
#CELL
  pure_quanta hole *
  page212_i87
#CELL
  pure_quanta hole *
  page212_i88
#CELL
  pure_quanta hole *
  page212_i89
#ISCELL
  pure_quanta_power universal_gnd *
  page212_i9
#ISCELL
  pure_quanta_power universal_gnd *
  page212_i90
#CELL
  pure_quanta hole *
  page212_i91
#ISCELL
  pure_quanta_power universal_gnd *
  page212_i92
#CELL
  pure_quanta hole *
  page212_i93
#CELL
  pure_quanta hole *
  page212_i94
